# S9S_MB_2U (Grand Teton) — schematic netlist excerpt (pin names and nets, part order shuffled) for the footprints in the layout excerpt that follows; sources: Cadence DE-HDL packaged netlist, KiCad conversion of 03242023_DA0F0TMBIJ0_F0T_Motherboard_J_brd_V01_OCP.brd

R4592  Q_RES  1K 1% CHIP  pkg 0402LF  page 195 : A = FM_BOARD_BMC_SKU_ID3 ; B = GND
C2392  Q_CAP  0.1UF 25V 10% EMPTY  pkg 0402  page 306 : A = U205_VDD ; B = GND

(kicad_pcb
	(version 20260206)
	(generator "pcbnew")
	(generator_version "10.0")
	(general
		(thickness 1.6)
		(legacy_teardrops no)
	)
	(paper "A4")
	(title_block
		(title "03242023_DA0F0TMBIJ0_F0T_Motherboard_J_brd_V01_OCP.brd")
		(comment 1 "Grand Teton / footprints 4029-4030 of 6105")
	)
	(layers
		(0 "F.Cu" signal "TOP")
		(4 "In1.Cu" signal "GND")
		(6 "In2.Cu" signal "IN1")
		(8 "In3.Cu" signal "GND1")
		(10 "In4.Cu" signal "IN2")
		(12 "In5.Cu" signal "GND2")
		(14 "In6.Cu" signal "IN3")
		(16 "In7.Cu" signal "GND3")
		(18 "In8.Cu" signal "VCC")
		(20 "In9.Cu" signal "VCC1")
		(22 "In10.Cu" signal "GND4")
		(24 "In11.Cu" signal "IN4")
		(26 "In12.Cu" signal "GND5")
		(28 "In13.Cu" signal "IN5")
		(30 "In14.Cu" signal "GND6")
		(32 "In15.Cu" signal "IN6")
		(34 "In16.Cu" signal "GND7")
		(2 "B.Cu" signal "BOTTOM")
		(9 "F.Adhes" user "F.Adhesive")
		(11 "B.Adhes" user "B.Adhesive")
		(13 "F.Paste" user "Package Geometry/Pastemask Top")
		(15 "B.Paste" user "Package Geometry/Pastemask Bottom")
		(5 "F.SilkS" user "Ref Des/Silkscreen Top")
		(7 "B.SilkS" user "Ref Des/Silkscreen Bottom")
		(1 "F.Mask" user "Board Geometry/Soldermask Top")
		(3 "B.Mask" user "Board Geometry/Soldermask Bottom")
		(17 "Dwgs.User" user "User.Drawings")
		(19 "Cmts.User" user "User.Comments")
		(21 "Eco1.User" user "User.Eco1")
		(23 "Eco2.User" user "User.Eco2")
		(25 "Edge.Cuts" user "Board Geometry/Outline")
		(27 "Margin" user)
		(31 "F.CrtYd" user "Package Geometry/Place Bound Top")
		(29 "B.CrtYd" user "Package Geometry/Place Bound Bottom")
		(35 "F.Fab" user "Ref Des/Assembly Top")
		(33 "B.Fab" user "Ref Des/Assembly Bottom")
	)
	(footprint ""
		(layer "F.Cu")
		(at 210.560158 -102.93604 180)
		(property "Reference" "C2392"
			(at 0 0 180)
			(layer "F.SilkS")
			(hide yes)
			(effects
				(font
					(size 1.27 1.27)
				)
			)
		)
		(property "Value" ""
			(at 0 0 180)
			(layer "F.Fab")
			(effects
				(font
					(size 1.27 1.27)
				)
			)
		)
		(duplicate_pad_numbers_are_jumpers no)
		(fp_line
			(start 0.7874 0.4064)
			(end -0.7874 0.4064)
			(stroke
				(width 0.1524)
				(type default)
			)
			(layer "F.SilkS")
		)
		(fp_line
			(start 0.7874 -0.4064)
			(end 0.7874 0.4064)
			(stroke
				(width 0.1524)
				(type default)
			)
			(layer "F.SilkS")
		)
		(fp_line
			(start -0.7874 0.4064)
			(end -0.7874 -0.4064)
			(stroke
				(width 0.1524)
				(type default)
			)
			(layer "F.SilkS")
		)
		(fp_line
			(start -0.7874 -0.4064)
			(end 0.7874 -0.4064)
			(stroke
				(width 0.1524)
				(type default)
			)
			(layer "F.SilkS")
		)
		(fp_line
			(start 0.67945 0.3048)
			(end 0.120396 0.3048)
			(stroke
				(width 0.1)
				(type default)
			)
			(layer "F.Fab")
		)
		(fp_line
			(start 0.67945 -0.3048)
			(end 0.67945 0.3048)
			(stroke
				(width 0.1)
				(type default)
			)
			(layer "F.Fab")
		)
		(fp_line
			(start 0.12065 -0.2794)
			(end 0.12065 -0.3048)
			(stroke
				(width 0.1)
				(type default)
			)
			(layer "F.Fab")
		)
		(fp_line
			(start 0.12065 -0.3048)
			(end 0.67945 -0.3048)
			(stroke
				(width 0.1)
				(type default)
			)
			(layer "F.Fab")
		)
		(fp_line
			(start 0.120396 0.3048)
			(end 0.120396 0.2794)
			(stroke
				(width 0.1)
				(type default)
			)
			(layer "F.Fab")
		)
		(fp_line
			(start 0.120396 0.2794)
			(end -0.12065 0.2794)
			(stroke
				(width 0.1)
				(type default)
			)
			(layer "F.Fab")
		)
		(fp_line
			(start -0.12065 0.3048)
			(end -0.67945 0.3048)
			(stroke
				(width 0.1)
				(type default)
			)
			(layer "F.Fab")
		)
		(fp_line
			(start -0.12065 0.2794)
			(end -0.12065 0.3048)
			(stroke
				(width 0.1)
				(type default)
			)
			(layer "F.Fab")
		)
		(fp_line
			(start -0.12065 -0.2794)
			(end 0.12065 -0.2794)
			(stroke
				(width 0.1)
				(type default)
			)
			(layer "F.Fab")
		)
		(fp_line
			(start -0.12065 -0.305054)
			(end -0.12065 -0.2794)
			(stroke
				(width 0.1)
				(type default)
			)
			(layer "F.Fab")
		)
		(fp_line
			(start -0.67945 0.3048)
			(end -0.67945 -0.305054)
			(stroke
				(width 0.1)
				(type default)
			)
			(layer "F.Fab")
		)
		(fp_line
			(start -0.67945 -0.305054)
			(end -0.12065 -0.305054)
			(stroke
				(width 0.1)
				(type default)
			)
			(layer "F.Fab")
		)
		(pad "1" smd circle
			(at -0.40005 0 180)
			(size 0 0)
			(layers "F.Cu" "F.Mask" "F.Paste")
			(net "U205_VDD")
		)
		(pad "2" smd circle
			(at 0.40005 0 180)
			(size 0 0)
			(layers "F.Cu" "F.Mask" "F.Paste")
			(net "GND")
		)
	)
	(footprint ""
		(layer "F.Cu")
		(at 179.2224 -94.338648 90)
		(property "Reference" "R4592"
			(at 0 0 90)
			(layer "F.SilkS")
			(hide yes)
			(effects
				(font
					(size 1.27 1.27)
				)
			)
		)
		(property "Value" ""
			(at 0 0 90)
			(layer "F.Fab")
			(effects
				(font
					(size 1.27 1.27)
				)
			)
		)
		(duplicate_pad_numbers_are_jumpers no)
		(fp_line
			(start 0.7874 -0.4064)
			(end 0.7874 0.4064)
			(stroke
				(width 0.1524)
				(type default)
			)
			(layer "F.SilkS")
		)
		(fp_line
			(start -0.7874 -0.4064)
			(end 0.7874 -0.4064)
			(stroke
				(width 0.1524)
				(type default)
			)
			(layer "F.SilkS")
		)
		(fp_line
			(start 0.7874 0.4064)
			(end -0.7874 0.4064)
			(stroke
				(width 0.1524)
				(type default)
			)
			(layer "F.SilkS")
		)
		(fp_line
			(start -0.7874 0.4064)
			(end -0.7874 -0.4064)
			(stroke
				(width 0.1524)
				(type default)
			)
			(layer "F.SilkS")
		)
		(fp_line
			(start -0.12065 -0.305054)
			(end -0.12065 -0.2794)
			(stroke
				(width 0.1)
				(type default)
			)
			(layer "F.Fab")
		)
		(fp_line
			(start -0.67945 -0.305054)
			(end -0.12065 -0.305054)
			(stroke
				(width 0.1)
				(type default)
			)
			(layer "F.Fab")
		)
		(fp_line
			(start 0.67945 -0.3048)
			(end 0.67945 0.3048)
			(stroke
				(width 0.1)
				(type default)
			)
			(layer "F.Fab")
		)
		(fp_line
			(start 0.12065 -0.3048)
			(end 0.67945 -0.3048)
			(stroke
				(width 0.1)
				(type default)
			)
			(layer "F.Fab")
		)
		(fp_line
			(start 0.12065 -0.2794)
			(end 0.12065 -0.3048)
			(stroke
				(width 0.1)
				(type default)
			)
			(layer "F.Fab")
		)
		(fp_line
			(start -0.12065 -0.2794)
			(end 0.12065 -0.2794)
			(stroke
				(width 0.1)
				(type default)
			)
			(layer "F.Fab")
		)
		(fp_line
			(start 0.120396 0.2794)
			(end -0.12065 0.2794)
			(stroke
				(width 0.1)
				(type default)
			)
			(layer "F.Fab")
		)
		(fp_line
			(start -0.12065 0.2794)
			(end -0.12065 0.3048)
			(stroke
				(width 0.1)
				(type default)
			)
			(layer "F.Fab")
		)
		(fp_line
			(start 0.67945 0.3048)
			(end 0.120396 0.3048)
			(stroke
				(width 0.1)
				(type default)
			)
			(layer "F.Fab")
		)
		(fp_line
			(start 0.120396 0.3048)
			(end 0.120396 0.2794)
			(stroke
				(width 0.1)
				(type default)
			)
			(layer "F.Fab")
		)
		(fp_line
			(start -0.12065 0.3048)
			(end -0.67945 0.3048)
			(stroke
				(width 0.1)
				(type default)
			)
			(layer "F.Fab")
		)
		(fp_line
			(start -0.67945 0.3048)
			(end -0.67945 -0.305054)
			(stroke
				(width 0.1)
				(type default)
			)
			(layer "F.Fab")
		)
		(pad "1" smd rect
			(at -0.40005 0 270)
			(size 0.4572 0.508)
			(layers "F.Cu" "F.Mask" "F.Paste")
			(net "FM_BOARD_BMC_SKU_ID3")
		)
		(pad "2" smd rect
			(at 0.40005 0 270)
			(size 0.4572 0.508)
			(layers "F.Cu" "F.Mask" "F.Paste")
			(net "GND")
		)
	)
)
